(kicad_pcb
	(version 20240108)
	(generator "pcbnew")
	(generator_version "8.0")
	(general
		(thickness 1.62)
		(legacy_teardrops no)
	)
	(paper "A4")
	(title_block
		(title "Jetson Orin Baseboard")
		(date "2025-03-12")
		(rev "1.3.4")
		(company "Antmicro Ltd")
		(comment 1 "www.antmicro.com")
		(comment 9 "footprints 331-335 of 677")
	)
	(layers
		(0 "F.Cu" signal)
		(1 "In1.Cu" signal)
		(2 "In2.Cu" signal)
		(3 "In3.Cu" signal)
		(4 "In4.Cu" jumper)
		(5 "In5.Cu" signal)
		(6 "In6.Cu" signal)
		(31 "B.Cu" signal)
		(32 "B.Adhes" user "B.Adhesive")
		(33 "F.Adhes" user "F.Adhesive")
		(34 "B.Paste" user)
		(35 "F.Paste" user)
		(36 "B.SilkS" user "B.Silkscreen")
		(37 "F.SilkS" user "F.Silkscreen")
		(38 "B.Mask" user)
		(39 "F.Mask" user)
		(40 "Dwgs.User" user "User.Drawings")
		(41 "Cmts.User" user "User.Comments")
		(42 "Eco1.User" user "User.Eco1")
		(43 "Eco2.User" user "User.Eco2")
		(44 "Edge.Cuts" user)
		(45 "Margin" user)
		(46 "B.CrtYd" user "B.Courtyard")
		(47 "F.CrtYd" user "F.Courtyard")
		(48 "B.Fab" user)
		(49 "F.Fab" user)
	)
	(footprint "antmicro-footprints:R_0402_1005Metric"
		(layer "B.Cu")
		(at 135.8 98.4)
		(descr "Resistor SMD 0402")
		(tags "resistor SMD 0402")
		(property "Reference" "R12"
			(at -0.75 0.45 180)
			(layer "B.SilkS")
			(effects
				(font
					(size 0.7 0.7)
					(thickness 0.15)
				)
				(justify left bottom mirror)
			)
		)
		(property "Value" "R_0R_0402"
			(at 0 -1.4 180)
			(layer "B.Fab")
			(effects
				(font
					(size 0.7 0.7)
					(thickness 0.15)
				)
				(justify left bottom mirror)
			)
		)
		(property "Footprint" "antmicro-footprints:R_0402_1005Metric"
			(at 0 0 0)
			(layer "F.Fab")
			(hide yes)
			(effects
				(font
					(size 1.27 1.27)
					(thickness 0.15)
				)
			)
		)
		(property "Datasheet" "https://industrial.panasonic.com/cdbs/www-data/pdf/RDA0000/AOA0000C301.pdf"
			(at 0 0 0)
			(layer "F.Fab")
			(hide yes)
			(effects
				(font
					(size 1.27 1.27)
					(thickness 0.15)
				)
			)
		)
		(property "Author" "Antmicro"
			(at 0 0 0)
			(layer "B.Fab")
			(hide yes)
			(effects
				(font
					(size 1 1)
					(thickness 0.15)
				)
				(justify mirror)
			)
		)
		(property "Current" "1A"
			(at 0 0 0)
			(layer "B.Fab")
			(hide yes)
			(effects
				(font
					(size 1 1)
					(thickness 0.15)
				)
				(justify mirror)
			)
		)
		(property "License" "Apache-2.0"
			(at 0 0 0)
			(layer "B.Fab")
			(hide yes)
			(effects
				(font
					(size 1 1)
					(thickness 0.15)
				)
				(justify mirror)
			)
		)
		(property "MPN" "ERJ2GE0R00X"
			(at 0 0 0)
			(layer "B.Fab")
			(hide yes)
			(effects
				(font
					(size 1 1)
					(thickness 0.15)
				)
				(justify mirror)
			)
		)
		(property "Manufacturer" "Panasonic"
			(at 0 0 0)
			(layer "B.Fab")
			(hide yes)
			(effects
				(font
					(size 1 1)
					(thickness 0.15)
				)
				(justify mirror)
			)
		)
		(property "Tolerance" ""
			(at 0 0 0)
			(layer "B.Fab")
			(hide yes)
			(effects
				(font
					(size 1 1)
					(thickness 0.15)
				)
				(justify mirror)
			)
		)
		(property "Val" "0R"
			(at 0 0 0)
			(layer "B.Fab")
			(hide yes)
			(effects
				(font
					(size 1 1)
					(thickness 0.15)
				)
				(justify mirror)
			)
		)
		(sheetname "SoM")
		(sheetfile "som.kicad_sch")
		(attr smd)
		(fp_rect
			(start -0.925 0.47)
			(end 0.925 -0.47)
			(stroke
				(width 0.05)
				(type default)
			)
			(fill none)
			(layer "B.CrtYd")
		)
		(fp_rect
			(start -0.5 0.25)
			(end 0.5 -0.25)
			(stroke
				(width 0.15)
				(type solid)
			)
			(fill none)
			(layer "B.Fab")
		)
		(fp_text user "License: Apache-2.0"
			(at -0.95 -5.169 180)
			(layer "B.Fab")
			(hide yes)
			(effects
				(font
					(size 0.7 0.7)
					(thickness 0.15)
				)
				(justify left bottom mirror)
			)
		)
		(fp_text user "${REFERENCE}"
			(at -0.95 -3.168 180)
			(layer "B.Fab")
			(hide yes)
			(effects
				(font
					(size 0.7 0.7)
					(thickness 0.15)
				)
				(justify left bottom mirror)
			)
		)
		(fp_text user "Author: Antmicro"
			(at -0.95 -4.169 180)
			(layer "B.Fab")
			(hide yes)
			(effects
				(font
					(size 0.7 0.7)
					(thickness 0.15)
				)
				(justify left bottom mirror)
			)
		)
		(pad "1" smd roundrect
			(at -0.48 0)
			(size 0.59 0.64)
			(layers "B.Cu" "B.Paste" "B.Mask")
			(roundrect_rratio 0.25)
			(net 743 "Net-(J15B-CAM0_PWDN)")
			(pintype "passive")
		)
		(pad "2" smd roundrect
			(at 0.48 0)
			(size 0.59 0.64)
			(layers "B.Cu" "B.Paste" "B.Mask")
			(roundrect_rratio 0.25)
			(net 217 "VSYNC_CAM0")
			(pintype "passive")
		)
	)
	(footprint "antmicro-footprints:R_0603_1608Metric"
		(layer "B.Cu")
		(at 70.9 79.4 180)
		(descr "Resistor SMD 0603")
		(tags "resistor SMD 0603")
		(property "Reference" "R273"
			(at -2.74 0.66 0)
			(layer "B.SilkS")
			(effects
				(font
					(size 0.7 0.7)
					(thickness 0.15)
				)
				(justify left bottom mirror)
			)
		)
		(property "Value" "R_0R_0603"
			(at 0 -1.6 0)
			(layer "B.Fab")
			(effects
				(font
					(size 0.7 0.7)
					(thickness 0.15)
				)
				(justify left bottom mirror)
			)
		)
		(property "Footprint" "antmicro-footprints:R_0603_1608Metric"
			(at 0 0 180)
			(layer "F.Fab")
			(hide yes)
			(effects
				(font
					(size 1.27 1.27)
					(thickness 0.15)
				)
			)
		)
		(property "Datasheet" "https://www.bourns.com/docs/product-datasheets/cr.pdf?sfvrsn=574d41f6_14"
			(at 0 0 180)
			(layer "F.Fab")
			(hide yes)
			(effects
				(font
					(size 1.27 1.27)
					(thickness 0.15)
				)
			)
		)
		(property "Author" "Antmicro"
			(at 141.8 158.8 0)
			(layer "B.Fab")
			(hide yes)
			(effects
				(font
					(size 1 1)
					(thickness 0.15)
				)
				(justify mirror)
			)
		)
		(property "Current" "1A"
			(at 141.8 158.8 0)
			(layer "B.Fab")
			(hide yes)
			(effects
				(font
					(size 1 1)
					(thickness 0.15)
				)
				(justify mirror)
			)
		)
		(property "License" "Apache-2.0"
			(at 141.8 158.8 0)
			(layer "B.Fab")
			(hide yes)
			(effects
				(font
					(size 1 1)
					(thickness 0.15)
				)
				(justify mirror)
			)
		)
		(property "MPN" "CR0603-J/-000ELF"
			(at 141.8 158.8 0)
			(layer "B.Fab")
			(hide yes)
			(effects
				(font
					(size 1 1)
					(thickness 0.15)
				)
				(justify mirror)
			)
		)
		(property "Manufacturer" "Bourns"
			(at 141.8 158.8 0)
			(layer "B.Fab")
			(hide yes)
			(effects
				(font
					(size 1 1)
					(thickness 0.15)
				)
				(justify mirror)
			)
		)
		(property "Tolerance" ""
			(at 141.8 158.8 0)
			(layer "B.Fab")
			(hide yes)
			(effects
				(font
					(size 1 1)
					(thickness 0.15)
				)
				(justify mirror)
			)
		)
		(property "Val" "0R"
			(at 141.8 158.8 0)
			(layer "B.Fab")
			(hide yes)
			(effects
				(font
					(size 1 1)
					(thickness 0.15)
				)
				(justify mirror)
			)
		)
		(sheetname "Supply")
		(sheetfile "supply.kicad_sch")
		(attr smd)
		(fp_line
			(start 0.15 0.4)
			(end -0.15 0.4)
			(stroke
				(width 0.15)
				(type solid)
			)
			(layer "B.SilkS")
		)
		(fp_line
			(start 0.15 -0.4)
			(end -0.15 -0.4)
			(stroke
				(width 0.15)
				(type solid)
			)
			(layer "B.SilkS")
		)
		(fp_rect
			(start -1.25 0.65)
			(end 1.25 -0.65)
			(stroke
				(width 0.05)
				(type solid)
			)
			(fill none)
			(layer "B.CrtYd")
		)
		(fp_rect
			(start -0.8 0.4)
			(end 0.8 -0.4)
			(stroke
				(width 0.15)
				(type solid)
			)
			(fill none)
			(layer "B.Fab")
		)
		(fp_text user "${REFERENCE}"
			(at -1.25 -3.898 0)
			(layer "B.Fab")
			(hide yes)
			(effects
				(font
					(size 0.7 0.7)
					(thickness 0.15)
				)
				(justify left bottom mirror)
			)
		)
		(fp_text user "Author: Antmicro"
			(at -1.25 -4.9 0)
			(layer "B.Fab")
			(hide yes)
			(effects
				(font
					(size 0.7 0.7)
					(thickness 0.15)
				)
				(justify left bottom mirror)
			)
		)
		(fp_text user "License: Apache-2.0"
			(at -1.25 -5.9 0)
			(layer "B.Fab")
			(hide yes)
			(effects
				(font
					(size 0.7 0.7)
					(thickness 0.15)
				)
				(justify left bottom mirror)
			)
		)
		(pad "1" smd roundrect
			(at -0.7 0 180)
			(size 0.8 1)
			(layers "B.Cu" "B.Paste" "B.Mask")
			(roundrect_rratio 0.2)
			(net 138 "/Supply/3V3_LDO")
			(pintype "passive")
		)
		(pad "2" smd roundrect
			(at 0.7 0 180)
			(size 0.8 1)
			(layers "B.Cu" "B.Paste" "B.Mask")
			(roundrect_rratio 0.2)
			(net 117 "3V3_STDB")
			(pintype "passive")
		)
	)
	(footprint "antmicro-footprints:TP_SMD_0.75mm"
		(layer "B.Cu")
		(at 100.14999 103.5508 180)
		(property "Reference" "TP41"
			(at 0 0.6 0)
			(layer "B.SilkS")
			(hide yes)
			(effects
				(font
					(size 0.7 0.7)
					(thickness 0.15)
				)
				(justify left bottom mirror)
			)
		)
		(property "Value" "TP_0.75mm_SMD"
			(at 0 -1.2 0)
			(layer "B.Fab")
			(effects
				(font
					(size 0.7 0.7)
					(thickness 0.15)
				)
				(justify left bottom mirror)
			)
		)
		(property "Footprint" "antmicro-footprints:TP_SMD_0.75mm"
			(at 0 0 180)
			(layer "F.Fab")
			(hide yes)
			(effects
				(font
					(size 1.27 1.27)
					(thickness 0.15)
				)
			)
		)
		(property "Author" "Antmicro"
			(at 200.29998 207.1016 0)
			(layer "B.Fab")
			(hide yes)
			(effects
				(font
					(size 1 1)
					(thickness 0.15)
				)
				(justify mirror)
			)
		)
		(property "License" "Apache-2.0"
			(at 200.29998 207.1016 0)
			(layer "B.Fab")
			(hide yes)
			(effects
				(font
					(size 1 1)
					(thickness 0.15)
				)
				(justify mirror)
			)
		)
		(property "MPN" ""
			(at 200.29998 207.1016 0)
			(layer "B.Fab")
			(hide yes)
			(effects
				(font
					(size 1 1)
					(thickness 0.15)
				)
				(justify mirror)
			)
		)
		(property "Manufacturer" ""
			(at 200.29998 207.1016 0)
			(layer "B.Fab")
			(hide yes)
			(effects
				(font
					(size 1 1)
					(thickness 0.15)
				)
				(justify mirror)
			)
		)
		(sheetname "CSI")
		(sheetfile "csi.kicad_sch")
		(attr exclude_from_pos_files exclude_from_bom)
		(fp_circle
			(center 0 0)
			(end 0.475 0)
			(stroke
				(width 0.05)
				(type default)
			)
			(fill none)
			(layer "B.CrtYd")
		)
		(fp_text user "License: Apache-2.0"
			(at -0.4 -5.101 0)
			(layer "B.Fab")
			(hide yes)
			(effects
				(font
					(size 0.7 0.7)
					(thickness 0.15)
				)
				(justify left bottom mirror)
			)
		)
		(fp_text user "Author: Antmicro"
			(at -0.4 -3.901 0)
			(layer "B.Fab")
			(hide yes)
			(effects
				(font
					(size 0.7 0.7)
					(thickness 0.15)
				)
				(justify left bottom mirror)
			)
		)
		(fp_text user "${REFERENCE}"
			(at -0.4 -2.7 0)
			(layer "B.Fab")
			(hide yes)
			(effects
				(font
					(size 0.7 0.7)
					(thickness 0.15)
				)
				(justify left bottom mirror)
			)
		)
		(pad "1" smd circle
			(at 0 0 180)
			(size 0.75 0.75)
			(layers "B.Cu" "B.Mask")
			(net 542 "/CSI/MUX_I2C_6_SCL")
			(pinfunction "1")
			(pintype "passive")
		)
	)
	(footprint "antmicro-footprints:C_0402_1005Metric"
		(layer "B.Cu")
		(at 90.025 82.55)
		(descr "Capacitor SMD 0402")
		(tags "capacitor SMD 0402")
		(property "Reference" "C139"
			(at -0.875 0.47 180)
			(layer "B.SilkS")
			(effects
				(font
					(size 0.7 0.7)
					(thickness 0.15)
				)
				(justify left bottom mirror)
			)
		)
		(property "Value" "C_100n_0402"
			(at 0 -1.4 180)
			(layer "B.Fab")
			(effects
				(font
					(size 0.7 0.7)
					(thickness 0.15)
				)
				(justify left bottom mirror)
			)
		)
		(property "Footprint" "antmicro-footprints:C_0402_1005Metric"
			(at 0 0 0)
			(layer "F.Fab")
			(hide yes)
			(effects
				(font
					(size 1.27 1.27)
					(thickness 0.15)
				)
			)
		)
		(property "Datasheet" "https://www.murata.com/products/productdetail?partno=GRM155R61H104KE14%23"
			(at 0 0 0)
			(layer "F.Fab")
			(hide yes)
			(effects
				(font
					(size 1.27 1.27)
					(thickness 0.15)
				)
			)
		)
		(property "Author" "Antmicro"
			(at 0 0 0)
			(layer "B.Fab")
			(hide yes)
			(effects
				(font
					(size 1 1)
					(thickness 0.15)
				)
				(justify mirror)
			)
		)
		(property "Dielectric" "X5R"
			(at 0 0 0)
			(layer "B.Fab")
			(hide yes)
			(effects
				(font
					(size 1 1)
					(thickness 0.15)
				)
				(justify mirror)
			)
		)
		(property "License" "Apache-2.0"
			(at 0 0 0)
			(layer "B.Fab")
			(hide yes)
			(effects
				(font
					(size 1 1)
					(thickness 0.15)
				)
				(justify mirror)
			)
		)
		(property "MPN" "GRM155R61H104KE14D"
			(at 0 0 0)
			(layer "B.Fab")
			(hide yes)
			(effects
				(font
					(size 1 1)
					(thickness 0.15)
				)
				(justify mirror)
			)
		)
		(property "Manufacturer" "Murata"
			(at 0 0 0)
			(layer "B.Fab")
			(hide yes)
			(effects
				(font
					(size 1 1)
					(thickness 0.15)
				)
				(justify mirror)
			)
		)
		(property "Val" "100n"
			(at 0 0 0)
			(layer "B.Fab")
			(hide yes)
			(effects
				(font
					(size 1 1)
					(thickness 0.15)
				)
				(justify mirror)
			)
		)
		(property "Voltage" "50V"
			(at 0 0 0)
			(layer "B.Fab")
			(hide yes)
			(effects
				(font
					(size 1 1)
					(thickness 0.15)
				)
				(justify mirror)
			)
		)
		(sheetname "HDMI")
		(sheetfile "hdmi.kicad_sch")
		(attr smd)
		(fp_rect
			(start -0.925 0.47)
			(end 0.925 -0.47)
			(stroke
				(width 0.05)
				(type default)
			)
			(fill none)
			(layer "B.CrtYd")
		)
		(fp_line
			(start -0.494 -0.248)
			(end 0.504 -0.248)
			(stroke
				(width 0.15)
				(type solid)
			)
			(layer "B.Fab")
		)
		(fp_line
			(start -0.494 0.25)
			(end -0.494 -0.248)
			(stroke
				(width 0.15)
				(type solid)
			)
			(layer "B.Fab")
		)
		(fp_line
			(start 0.504 -0.248)
			(end 0.504 0.25)
			(stroke
				(width 0.15)
				(type solid)
			)
			(layer "B.Fab")
		)
		(fp_line
			(start 0.504 0.25)
			(end -0.494 0.25)
			(stroke
				(width 0.15)
				(type solid)
			)
			(layer "B.Fab")
		)
		(fp_text user "${REFERENCE}"
			(at -0.932 -3.168 180)
			(layer "B.Fab")
			(hide yes)
			(effects
				(font
					(size 0.7 0.7)
					(thickness 0.15)
				)
				(justify left bottom mirror)
			)
		)
		(fp_text user "Author: Antmicro"
			(at -0.932 -4.17 180)
			(layer "B.Fab")
			(hide yes)
			(effects
				(font
					(size 0.7 0.7)
					(thickness 0.15)
				)
				(justify left bottom mirror)
			)
		)
		(fp_text user "License: Apache-2.0"
			(at -0.932 -5.17 180)
			(layer "B.Fab")
			(hide yes)
			(effects
				(font
					(size 0.7 0.7)
					(thickness 0.15)
				)
				(justify left bottom mirror)
			)
		)
		(pad "1" smd roundrect
			(at -0.48 0)
			(size 0.59 0.64)
			(layers "B.Cu" "B.Paste" "B.Mask")
			(roundrect_rratio 0.25)
			(net 36 "DP1_AUX_P")
			(pintype "passive")
		)
		(pad "2" smd roundrect
			(at 0.48 0)
			(size 0.59 0.64)
			(layers "B.Cu" "B.Paste" "B.Mask")
			(roundrect_rratio 0.25)
			(net 669 "/HDMI/DP_MUX_AUX_B+")
			(pintype "passive")
		)
	)
	(footprint "antmicro-footprints:R_0402_1005Metric"
		(layer "B.Cu")
		(at 103.25 113.5 -90)
		(descr "Resistor SMD 0402")
		(tags "resistor SMD 0402")
		(property "Reference" "R128"
			(at -1.4 0.45 90)
			(layer "B.SilkS")
			(effects
				(font
					(size 0.7 0.7)
					(thickness 0.15)
				)
				(justify left bottom mirror)
			)
		)
		(property "Value" "R_887k_0402"
			(at 0 -1.4 90)
			(layer "B.Fab")
			(effects
				(font
					(size 0.7 0.7)
					(thickness 0.15)
				)
				(justify left bottom mirror)
			)
		)
		(property "Footprint" "antmicro-footprints:R_0402_1005Metric"
			(at 0 0 -90)
			(layer "F.Fab")
			(hide yes)
			(effects
				(font
					(size 1.27 1.27)
					(thickness 0.15)
				)
			)
		)
		(property "Datasheet" "https://eu.mouser.com/datasheet/2/315/AOA0000C304-1149620.pdf"
			(at 0 0 -90)
			(layer "F.Fab")
			(hide yes)
			(effects
				(font
					(size 1.27 1.27)
					(thickness 0.15)
				)
			)
		)
		(property "Author" "Antmicro"
			(at -10.25 216.75 0)
			(layer "B.Fab")
			(hide yes)
			(effects
				(font
					(size 1 1)
					(thickness 0.15)
				)
				(justify mirror)
			)
		)
		(property "License" "Apache-2.0"
			(at -10.25 216.75 0)
			(layer "B.Fab")
			(hide yes)
			(effects
				(font
					(size 1 1)
					(thickness 0.15)
				)
				(justify mirror)
			)
		)
		(property "MPN" "ERJ-2RKF8873X"
			(at -10.25 216.75 0)
			(layer "B.Fab")
			(hide yes)
			(effects
				(font
					(size 1 1)
					(thickness 0.15)
				)
				(justify mirror)
			)
		)
		(property "Manufacturer" "Panasonic"
			(at -10.25 216.75 0)
			(layer "B.Fab")
			(hide yes)
			(effects
				(font
					(size 1 1)
					(thickness 0.15)
				)
				(justify mirror)
			)
		)
		(property "Tolerance" "1%"
			(at -10.25 216.75 0)
			(layer "B.Fab")
			(hide yes)
			(effects
				(font
					(size 1 1)
					(thickness 0.15)
				)
				(justify mirror)
			)
		)
		(property "Val" "887k"
			(at -10.25 216.75 0)
			(layer "B.Fab")
			(hide yes)
			(effects
				(font
					(size 1 1)
					(thickness 0.15)
				)
				(justify mirror)
			)
		)
		(sheetname "USB3")
		(sheetfile "usb3.kicad_sch")
		(attr smd)
		(fp_rect
			(start -0.925 0.47)
			(end 0.925 -0.47)
			(stroke
				(width 0.05)
				(type default)
			)
			(fill none)
			(layer "B.CrtYd")
		)
		(fp_rect
			(start -0.5 0.25)
			(end 0.5 -0.25)
			(stroke
				(width 0.15)
				(type solid)
			)
			(fill none)
			(layer "B.Fab")
		)
		(fp_text user "${REFERENCE}"
			(at -0.95 -3.168 90)
			(layer "B.Fab")
			(hide yes)
			(effects
				(font
					(size 0.7 0.7)
					(thickness 0.15)
				)
				(justify left bottom mirror)
			)
		)
		(fp_text user "License: Apache-2.0"
			(at -0.95 -5.169 90)
			(layer "B.Fab")
			(hide yes)
			(effects
				(font
					(size 0.7 0.7)
					(thickness 0.15)
				)
				(justify left bottom mirror)
			)
		)
		(fp_text user "Author: Antmicro"
			(at -0.95 -4.169 90)
			(layer "B.Fab")
			(hide yes)
			(effects
				(font
					(size 0.7 0.7)
					(thickness 0.15)
				)
				(justify left bottom mirror)
			)
		)
		(pad "1" smd roundrect
			(at -0.48 0 270)
			(size 0.59 0.64)
			(layers "B.Cu" "B.Paste" "B.Mask")
			(roundrect_rratio 0.25)
			(net 365 "/USB3/USBC1_VBUS_DET")
			(pintype "passive")
		)
		(pad "2" smd roundrect
			(at 0.48 0 270)
			(size 0.59 0.64)
			(layers "B.Cu" "B.Paste" "B.Mask")
			(roundrect_rratio 0.25)
			(net 270 "/USB3/USBC1_VBUS")
			(pintype "passive")
		)
	)
)
